# BASEBOARD_FAB2 (Tioga Pass) — schematic netlist excerpt (pin names and nets, part order shuffled) for the footprints in the layout excerpt that follows; sources: Cadence DE-HDL packaged netlist, KiCad conversion of Wiwynn_Tioga_Pass_MB.brd

EU9E1  SPRINGVILLE  IC  pkg SM1  page 139
  LAN_PWR_GOOD  = PU_SPRV_LAN_PWR_GOOD
  NC_SI_CLK_IN  = CLK_50M_CKMNG_SPRVLLE
  NC_SI_CRS_DV  = RMII_BMC_PCH_SPRNGVLLE_CRSDV_R
  JTAG_TDO  = PU_JTAG_SPRV_TDO
  NC_SI_RXD1  = RMII_SPRNGVLLE_BMC_PCH_RXD1_R
  NC_SI_RXD0  = RMII_SPRNGVLLE_BMC_PCH_RXD0_R
  NC_SI_TX_EN  = RMII_BMC_PCH_SPRNGVLLE_TXEN
  NC_SI_TXD1  = RMII_BMC_PCH_SPRNGVLLE_TXD1
  NC_SI_TXD0  = RMII_BMC_PCH_SPRNGVLLE_TXD0
  VDD3P3(4)  = P3V3_STBY
  VDD0P9(2)  = P0V9_LAN
  NVM_SI  = SPI_NIC_MOSI_R
  NVM_SK  = SPI_NIC_SCLK_R
  NVM_SO  = SPI_NIC_MISO
  NVM_CS_N  = SPI_NIC_CS_R_N
  PE_WAKE_N  = FM_PE_SPRV_WAKE_N
  PE_RST_N  = RST_PLTRST_SPRV_R_N
  JTAG_TMS  = PU_JTAG_SPRV_TMS
  JTAG_CLK  = PU_JTAG_SPRV_TCK
  PE_TN  = PE_PCH_SPRV_RX_DN
  PE_TP  = PE_PCH_SPRV_RX_DP
  NC  = NC
  PE_RN  = PE_PCH_SPRV_TX_C_DN
  PE_RP  = PE_PCH_SPRV_TX_C_DP
  PECLKN  = CLK_100M_SPRV_DN
  PECLKP  = CLK_100M_SPRV_DP
  VDD3P3(3)  = P3V3_STBY
  DEV_OFF_N  = PU_DEV_OFF_N
  JTAG_TDI  = PU_JTAG_SPRV_TDI
  LED1  = LED_LAN_1_N
  LED0  = LED_LAN_0_N
  VDD0P9(1)  = P0V9_LAN
  LED2  = LED_LAN_2_N
  SMB_CLK  = SMB_SPRINGVILLE_STBY_LVC3_SCL
  SMB_ALRT_N  = IRQ_LOM_ALERT_N
  SMB_DATA  = SMB_SPRINGVILLE_STBY_LVC3_SDA
  CBOT  = A_CBOT
  VDD0P9_OUT  = P0V9_LAN_I210
  VDD1P5_OUT  = P1V5_LAN
  CTOP  = A_CTOP
  VDD3P3(2)  = P3V3_STBY
  VDD0P9(3)  = P0V9_LAN
  NC_SI_ARB_IN  = RMII_PCH_SPRNGVLLE_ARB_OUT
  NC_SI_ARB_OUT  = RMII_PCH_SPRNGVLLE_ARB_IN_R
  XTAL2  = XTAL_25MHZ_OUT
  XTAL1  = XTAL_25MHZ_IN_R
  VDD1P5(1)  = P1V5_LAN
  RSET  = PD_SPRV_RSET
  MDI_MINUS3_SERN  = NIC_SER_N_MDI_3_DN
  MDI_PLUS3_SERP  = NIC_SER_P_MDI_3_DP
  VDD3P3(1)  = P3V3_STBY_P1V5_LAN_I210
  MDI_MINUS2_SETN  = NIC_SET_N_MDI_2_DN
  MDI_PLUS2_SETP  = NIC_SET_P_MDI_2_DP
  MDI_MINUS1_SRDS_SIG_DET  = NIC_MDI_SPRV_RJ45_1_DN
  MDI_PLUS1_SFP_I2C_CLK  = NIC_MDI_SPRV_RJ45_1_DP
  VDD1P5(0)  = P1V5_LAN_I210
  MDI_MINUS0_SFP_I2C_DATA  = NIC_MDI_SPRV_RJ45_0_DN
  MDI_PLUS0_NC  = NIC_MDI_SPRV_RJ45_0_DP
  VDD0P9(0)  = P0V9_LAN
  SDP3  = TP_SPRV_SDP3
  SDP1_PCIE_DIS_SDP1  = FM_1GB_LOM_DISABLE_N
  SDP2  = TP_SPRV_SDP2
  SDP0  = TP_SPRV_SDP0
  VDD3P3(0)  = P3V3_STBY
  GND  = GND

(kicad_pcb
	(version 20260206)
	(generator "pcbnew")
	(generator_version "10.0")
	(general
		(thickness 1.6)
		(legacy_teardrops no)
	)
	(paper "A4")
	(title_block
		(title "Wiwynn_Tioga_Pass_MB.brd")
		(comment 1 "Tioga Pass / footprint 1033 of 4770 (EU9E1), pads 35-51 of 65")
	)
	(layers
		(0 "F.Cu" signal "TOP")
		(4 "In1.Cu" signal "L2GND")
		(6 "In2.Cu" signal "L3")
		(8 "In3.Cu" signal "L4GND")
		(10 "In4.Cu" signal "L5")
		(12 "In5.Cu" signal "L6GND")
		(14 "In6.Cu" signal "L7VCC")
		(16 "In7.Cu" signal "L8VCC")
		(18 "In8.Cu" signal "L9GND")
		(20 "In9.Cu" signal "L10")
		(22 "In10.Cu" signal "L11GND")
		(24 "In11.Cu" signal "L12")
		(26 "In12.Cu" signal "L13GND")
		(2 "B.Cu" signal "BOTTOM")
		(9 "F.Adhes" user "F.Adhesive")
		(11 "B.Adhes" user "B.Adhesive")
		(13 "F.Paste" user "Package Geometry/Pastemask Top")
		(15 "B.Paste" user "Package Geometry/Pastemask Bottom")
		(5 "F.SilkS" user "Ref Des/Silkscreen Top")
		(7 "B.SilkS" user "Ref Des/Silkscreen Bottom")
		(1 "F.Mask" user "Board Geometry/Soldermask Top")
		(3 "B.Mask" user "Board Geometry/Soldermask Bottom")
		(17 "Dwgs.User" user "User.Drawings")
		(19 "Cmts.User" user "User.Comments")
		(21 "Eco1.User" user "User.Eco1")
		(23 "Eco2.User" user "User.Eco2")
		(25 "Edge.Cuts" user "Board Geometry/Outline")
		(27 "Margin" user)
		(31 "F.CrtYd" user "Package Geometry/Place Bound Top")
		(29 "B.CrtYd" user "Package Geometry/Place Bound Bottom")
		(35 "F.Fab" user "Ref Des/Assembly Top")
		(33 "B.Fab" user "Ref Des/Assembly Bottom")
	)
	(footprint ""
		(layer "F.Cu")
		(at 484.251 -43.9674 180)
		(property "Reference" "EU9E1"
			(at 7.2644 -5.49529 0)
			(unlocked yes)
			(layer "F.SilkS")
			(effects
				(font
					(size 0.7874 0.5842)
					(thickness 0.1524)
				)
				(justify left)
			)
		)
		(property "Value" ""
			(at 0 0 180)
			(layer "F.Fab")
			(effects
				(font
					(size 1.27 1.27)
				)
			)
		)
		(duplicate_pad_numbers_are_jumpers no)
		(pad "35" smd custom
			(at 4.3688 2.750058 180)
			(size 0.0762 0.0762)
			(layers "F.Cu" "F.Mask" "F.Paste")
			(net "IRQ_LOM_ALERT_N")
			(options
				(clearance outline)
				(anchor circle)
			)
			(primitives
				(gr_poly
					(pts
						(xy 0.381 0.1524)
						(arc
							(start -0.2286 0.1524)
							(mid -0.381 0)
							(end -0.2286 -0.1524)
						)
						(xy 0.381 -0.1524)
					)
					(width 0)
					(fill yes)
				)
			)
		)
		(pad "36" smd custom
			(at 4.3688 2.249932 180)
			(size 0.0762 0.0762)
			(layers "F.Cu" "F.Mask" "F.Paste")
			(net "SMB_SPRINGVILLE_STBY_LVC3_SDA")
			(options
				(clearance outline)
				(anchor circle)
			)
			(primitives
				(gr_poly
					(pts
						(xy 0.381 0.1524)
						(arc
							(start -0.2286 0.1524)
							(mid -0.381 0)
							(end -0.2286 -0.1524)
						)
						(xy 0.381 -0.1524)
					)
					(width 0)
					(fill yes)
				)
			)
		)
		(pad "37" smd custom
			(at 4.3688 1.75006 180)
			(size 0.0762 0.0762)
			(layers "F.Cu" "F.Mask" "F.Paste")
			(net "A_CBOT")
			(options
				(clearance outline)
				(anchor circle)
			)
			(primitives
				(gr_poly
					(pts
						(xy 0.381 0.1524)
						(arc
							(start -0.2286 0.1524)
							(mid -0.381 0)
							(end -0.2286 -0.1524)
						)
						(xy 0.381 -0.1524)
					)
					(width 0)
					(fill yes)
				)
			)
		)
		(pad "38" smd custom
			(at 4.3688 1.249934 180)
			(size 0.0762 0.0762)
			(layers "F.Cu" "F.Mask" "F.Paste")
			(net "P0V9_LAN_I210")
			(options
				(clearance outline)
				(anchor circle)
			)
			(primitives
				(gr_poly
					(pts
						(xy 0.381 0.1524)
						(arc
							(start -0.2286 0.1524)
							(mid -0.381 0)
							(end -0.2286 -0.1524)
						)
						(xy 0.381 -0.1524)
					)
					(width 0)
					(fill yes)
				)
			)
		)
		(pad "39" smd custom
			(at 4.3688 0.750062 180)
			(size 0.0762 0.0762)
			(layers "F.Cu" "F.Mask" "F.Paste")
			(net "P1V5_LAN")
			(options
				(clearance outline)
				(anchor circle)
			)
			(primitives
				(gr_poly
					(pts
						(xy 0.381 0.1524)
						(arc
							(start -0.2286 0.1524)
							(mid -0.381 0)
							(end -0.2286 -0.1524)
						)
						(xy 0.381 -0.1524)
					)
					(width 0)
					(fill yes)
				)
			)
		)
		(pad "40" smd custom
			(at 4.3688 0.249936 180)
			(size 0.0762 0.0762)
			(layers "F.Cu" "F.Mask" "F.Paste")
			(net "A_CTOP")
			(options
				(clearance outline)
				(anchor circle)
			)
			(primitives
				(gr_poly
					(pts
						(xy 0.381 0.1524)
						(arc
							(start -0.2286 0.1524)
							(mid -0.381 0)
							(end -0.2286 -0.1524)
						)
						(xy 0.381 -0.1524)
					)
					(width 0)
					(fill yes)
				)
			)
		)
		(pad "41" smd custom
			(at 4.3688 -0.249936 180)
			(size 0.0762 0.0762)
			(layers "F.Cu" "F.Mask" "F.Paste")
			(net "P3V3_STBY")
			(options
				(clearance outline)
				(anchor circle)
			)
			(primitives
				(gr_poly
					(pts
						(xy 0.381 0.1524)
						(arc
							(start -0.2286 0.1524)
							(mid -0.381 0)
							(end -0.2286 -0.1524)
						)
						(xy 0.381 -0.1524)
					)
					(width 0)
					(fill yes)
				)
			)
		)
		(pad "42" smd custom
			(at 4.3688 -0.750062 180)
			(size 0.0762 0.0762)
			(layers "F.Cu" "F.Mask" "F.Paste")
			(net "P0V9_LAN")
			(options
				(clearance outline)
				(anchor circle)
			)
			(primitives
				(gr_poly
					(pts
						(xy 0.381 0.1524)
						(arc
							(start -0.2286 0.1524)
							(mid -0.381 0)
							(end -0.2286 -0.1524)
						)
						(xy 0.381 -0.1524)
					)
					(width 0)
					(fill yes)
				)
			)
		)
		(pad "43" smd custom
			(at 4.3688 -1.249934 180)
			(size 0.0762 0.0762)
			(layers "F.Cu" "F.Mask" "F.Paste")
			(net "RMII_PCH_SPRNGVLLE_ARB_OUT")
			(options
				(clearance outline)
				(anchor circle)
			)
			(primitives
				(gr_poly
					(pts
						(xy 0.381 0.1524)
						(arc
							(start -0.2286 0.1524)
							(mid -0.381 0)
							(end -0.2286 -0.1524)
						)
						(xy 0.381 -0.1524)
					)
					(width 0)
					(fill yes)
				)
			)
		)
		(pad "44" smd custom
			(at 4.3688 -1.75006 180)
			(size 0.0762 0.0762)
			(layers "F.Cu" "F.Mask" "F.Paste")
			(net "RMII_PCH_SPRNGVLLE_ARB_IN_R")
			(options
				(clearance outline)
				(anchor circle)
			)
			(primitives
				(gr_poly
					(pts
						(xy 0.381 0.1524)
						(arc
							(start -0.2286 0.1524)
							(mid -0.381 0)
							(end -0.2286 -0.1524)
						)
						(xy 0.381 -0.1524)
					)
					(width 0)
					(fill yes)
				)
			)
		)
		(pad "45" smd custom
			(at 4.3688 -2.249932 180)
			(size 0.0762 0.0762)
			(layers "F.Cu" "F.Mask" "F.Paste")
			(net "XTAL_25MHZ_OUT")
			(options
				(clearance outline)
				(anchor circle)
			)
			(primitives
				(gr_poly
					(pts
						(xy 0.381 0.1524)
						(arc
							(start -0.2286 0.1524)
							(mid -0.381 0)
							(end -0.2286 -0.1524)
						)
						(xy 0.381 -0.1524)
					)
					(width 0)
					(fill yes)
				)
			)
		)
		(pad "46" smd custom
			(at 4.3688 -2.750058 180)
			(size 0.0762 0.0762)
			(layers "F.Cu" "F.Mask" "F.Paste")
			(net "XTAL_25MHZ_IN_R")
			(options
				(clearance outline)
				(anchor circle)
			)
			(primitives
				(gr_poly
					(pts
						(xy 0.381 0.1524)
						(arc
							(start -0.2286 0.1524)
							(mid -0.381 0)
							(end -0.2286 -0.1524)
						)
						(xy 0.381 -0.1524)
					)
					(width 0)
					(fill yes)
				)
			)
		)
		(pad "47" smd custom
			(at 4.3688 -3.24993 180)
			(size 0.0762 0.0762)
			(layers "F.Cu" "F.Mask" "F.Paste")
			(net "P1V5_LAN")
			(options
				(clearance outline)
				(anchor circle)
			)
			(primitives
				(gr_poly
					(pts
						(xy 0.381 0.1524)
						(arc
							(start -0.2286 0.1524)
							(mid -0.381 0)
							(end -0.2286 -0.1524)
						)
						(xy 0.381 -0.1524)
					)
					(width 0)
					(fill yes)
				)
			)
		)
		(pad "48" smd custom
			(at 4.3688 -3.750056 180)
			(size 0.0762 0.0762)
			(layers "F.Cu" "F.Mask" "F.Paste")
			(net "PD_SPRV_RSET")
			(options
				(clearance outline)
				(anchor circle)
			)
			(primitives
				(gr_poly
					(pts
						(xy 0.381 0.1524)
						(arc
							(start -0.2286 0.1524)
							(mid -0.381 0)
							(end -0.2286 -0.1524)
						)
						(xy 0.381 -0.1524)
					)
					(width 0)
					(fill yes)
				)
			)
		)
		(pad "49" smd custom
			(at 3.750056 -4.3688 180)
			(size 0.0762 0.0762)
			(layers "F.Cu" "F.Mask" "F.Paste")
			(net "NIC_SER_N_MDI_3_DN")
			(options
				(clearance outline)
				(anchor circle)
			)
			(primitives
				(gr_poly
					(pts
						(xy 0.1524 -0.381)
						(arc
							(start 0.1524 0.2286)
							(mid 0 0.381)
							(end -0.1524 0.2286)
						)
						(xy -0.1524 -0.381)
					)
					(width 0)
					(fill yes)
				)
			)
		)
		(pad "50" smd custom
			(at 3.24993 -4.3688 180)
			(size 0.0762 0.0762)
			(layers "F.Cu" "F.Mask" "F.Paste")
			(net "NIC_SER_P_MDI_3_DP")
			(options
				(clearance outline)
				(anchor circle)
			)
			(primitives
				(gr_poly
					(pts
						(xy 0.1524 -0.381)
						(arc
							(start 0.1524 0.2286)
							(mid 0 0.381)
							(end -0.1524 0.2286)
						)
						(xy -0.1524 -0.381)
					)
					(width 0)
					(fill yes)
				)
			)
		)
		(pad "51" smd custom
			(at 2.750058 -4.3688 180)
			(size 0.0762 0.0762)
			(layers "F.Cu" "F.Mask" "F.Paste")
			(net "P3V3_STBY_P1V5_LAN_I210")
			(options
				(clearance outline)
				(anchor circle)
			)
			(primitives
				(gr_poly
					(pts
						(xy 0.1524 -0.381)
						(arc
							(start 0.1524 0.2286)
							(mid 0 0.381)
							(end -0.1524 0.2286)
						)
						(xy -0.1524 -0.381)
					)
					(width 0)
					(fill yes)
				)
			)
		)
	)
)
